# T6G (Grand Teton) — schematic netlist excerpt (pin names and nets, part order shuffled) for the footprints in the layout excerpt that follows; sources: Cadence DE-HDL packaged netlist, KiCad conversion of 04192023_DAF0TMB3IC0_F0TG_MB_C_brd_V02_OCP.brd

R2311  Q_RES  0 5% EMPTY  pkg 0402LF  page 159 : A = I3C_0_SPD_DDRAF_CPU0_R_SDA ; B = I3C_SPD_DDRAF_CPU0_BYPASS_SDA

(kicad_pcb
	(version 20260206)
	(generator "pcbnew")
	(generator_version "10.0")
	(general
		(thickness 1.6)
		(legacy_teardrops no)
	)
	(paper "A4")
	(title_block
		(title "04192023_DAF0TMB3IC0_F0TG_MB_C_brd_V02_OCP.brd")
		(comment 1 "Grand Teton / footprints 4689-4689 of 8354")
	)
	(layers
		(0 "F.Cu" signal "TOP")
		(4 "In1.Cu" signal "GND")
		(6 "In2.Cu" signal "IN1")
		(8 "In3.Cu" signal "GND1")
		(10 "In4.Cu" signal "IN2")
		(12 "In5.Cu" signal "GND2")
		(14 "In6.Cu" signal "IN3")
		(16 "In7.Cu" signal "GND3")
		(18 "In8.Cu" signal "VCC")
		(20 "In9.Cu" signal "VCC1")
		(22 "In10.Cu" signal "GND4")
		(24 "In11.Cu" signal "IN4")
		(26 "In12.Cu" signal "GND5")
		(28 "In13.Cu" signal "IN5")
		(30 "In14.Cu" signal "GND6")
		(32 "In15.Cu" signal "IN6")
		(34 "In16.Cu" signal "GND7")
		(2 "B.Cu" signal "BOTTOM")
		(9 "F.Adhes" user "F.Adhesive")
		(11 "B.Adhes" user "B.Adhesive")
		(13 "F.Paste" user "Package Geometry/Pastemask Top")
		(15 "B.Paste" user "Package Geometry/Pastemask Bottom")
		(5 "F.SilkS" user "Ref Des/Silkscreen Top")
		(7 "B.SilkS" user "Ref Des/Silkscreen Bottom")
		(1 "F.Mask" user "Board Geometry/Soldermask Top")
		(3 "B.Mask" user "Board Geometry/Soldermask Bottom")
		(17 "Dwgs.User" user "User.Drawings")
		(19 "Cmts.User" user "User.Comments")
		(21 "Eco1.User" user "User.Eco1")
		(23 "Eco2.User" user "User.Eco2")
		(25 "Edge.Cuts" user "Board Geometry/Outline")
		(27 "Margin" user)
		(31 "F.CrtYd" user "Package Geometry/Place Bound Top")
		(29 "B.CrtYd" user "Package Geometry/Place Bound Bottom")
		(35 "F.Fab" user "Ref Des/Assembly Top")
		(33 "B.Fab" user "Ref Des/Assembly Bottom")
	)
	(footprint ""
		(layer "F.Cu")
		(at 319.22339 -192.09766 -90)
		(property "Reference" "R2311"
			(at 0 0 270)
			(layer "F.SilkS")
			(hide yes)
			(effects
				(font
					(size 1.27 1.27)
				)
			)
		)
		(property "Value" ""
			(at 0 0 270)
			(layer "F.Fab")
			(effects
				(font
					(size 1.27 1.27)
				)
			)
		)
		(duplicate_pad_numbers_are_jumpers no)
		(fp_line
			(start -0.7874 0.4064)
			(end -0.7874 -0.4064)
			(stroke
				(width 0.1524)
				(type default)
			)
			(layer "F.SilkS")
		)
		(fp_line
			(start 0.7874 0.4064)
			(end -0.7874 0.4064)
			(stroke
				(width 0.1524)
				(type default)
			)
			(layer "F.SilkS")
		)
		(fp_line
			(start -0.7874 -0.4064)
			(end 0.7874 -0.4064)
			(stroke
				(width 0.1524)
				(type default)
			)
			(layer "F.SilkS")
		)
		(fp_line
			(start 0.7874 -0.4064)
			(end 0.7874 0.4064)
			(stroke
				(width 0.1524)
				(type default)
			)
			(layer "F.SilkS")
		)
		(fp_line
			(start -0.67945 0.3048)
			(end -0.67945 -0.305054)
			(stroke
				(width 0.1)
				(type default)
			)
			(layer "F.Fab")
		)
		(fp_line
			(start -0.12065 0.3048)
			(end -0.67945 0.3048)
			(stroke
				(width 0.1)
				(type default)
			)
			(layer "F.Fab")
		)
		(fp_line
			(start 0.120396 0.3048)
			(end 0.120396 0.2794)
			(stroke
				(width 0.1)
				(type default)
			)
			(layer "F.Fab")
		)
		(fp_line
			(start 0.67945 0.3048)
			(end 0.120396 0.3048)
			(stroke
				(width 0.1)
				(type default)
			)
			(layer "F.Fab")
		)
		(fp_line
			(start -0.12065 0.2794)
			(end -0.12065 0.3048)
			(stroke
				(width 0.1)
				(type default)
			)
			(layer "F.Fab")
		)
		(fp_line
			(start 0.120396 0.2794)
			(end -0.12065 0.2794)
			(stroke
				(width 0.1)
				(type default)
			)
			(layer "F.Fab")
		)
		(fp_line
			(start -0.12065 -0.2794)
			(end 0.12065 -0.2794)
			(stroke
				(width 0.1)
				(type default)
			)
			(layer "F.Fab")
		)
		(fp_line
			(start 0.12065 -0.2794)
			(end 0.12065 -0.3048)
			(stroke
				(width 0.1)
				(type default)
			)
			(layer "F.Fab")
		)
		(fp_line
			(start 0.12065 -0.3048)
			(end 0.67945 -0.3048)
			(stroke
				(width 0.1)
				(type default)
			)
			(layer "F.Fab")
		)
		(fp_line
			(start 0.67945 -0.3048)
			(end 0.67945 0.3048)
			(stroke
				(width 0.1)
				(type default)
			)
			(layer "F.Fab")
		)
		(fp_line
			(start -0.67945 -0.305054)
			(end -0.12065 -0.305054)
			(stroke
				(width 0.1)
				(type default)
			)
			(layer "F.Fab")
		)
		(fp_line
			(start -0.12065 -0.305054)
			(end -0.12065 -0.2794)
			(stroke
				(width 0.1)
				(type default)
			)
			(layer "F.Fab")
		)
		(pad "1" smd rect
			(at -0.40005 0 90)
			(size 0.4572 0.508)
			(layers "F.Cu" "F.Mask" "F.Paste")
			(net "I3C_0_SPD_DDRAF_CPU0_R_SDA")
		)
		(pad "2" smd rect
			(at 0.40005 0 90)
			(size 0.4572 0.508)
			(layers "F.Cu" "F.Mask" "F.Paste")
			(net "I3C_SPD_DDRAF_CPU0_BYPASS_SDA")
		)
	)
)
